(kicad_pcb
	(version 20260206)
	(generator "pcbnew")
	(generator_version "10.0")
	(general
		(thickness 1.6)
		(legacy_teardrops no)
	)
	(paper "A4")
	(title_block
		(title "01162023_DA0F0TEBIF0_F0T_Expander_BD_F_brd_V02_OCP.brd")
		(comment 1 "Grand Teton / footprints 5239-5245 of 9728")
	)
	(layers
		(0 "F.Cu" signal "TOP")
		(4 "In1.Cu" signal "GND")
		(6 "In2.Cu" signal "VCC")
		(8 "In3.Cu" signal "VCC1")
		(10 "In4.Cu" signal "GND1")
		(12 "In5.Cu" signal "IN1")
		(14 "In6.Cu" signal "GND2")
		(16 "In7.Cu" signal "IN2")
		(18 "In8.Cu" signal "GND3")
		(20 "In9.Cu" signal "IN3")
		(22 "In10.Cu" signal "GND4")
		(24 "In11.Cu" signal "IN4")
		(26 "In12.Cu" signal "GND5")
		(28 "In13.Cu" signal "IN5")
		(30 "In14.Cu" signal "GND6")
		(32 "In15.Cu" signal "IN6")
		(34 "In16.Cu" signal "GND7")
		(2 "B.Cu" signal "BOTTOM")
		(9 "F.Adhes" user "F.Adhesive")
		(11 "B.Adhes" user "B.Adhesive")
		(13 "F.Paste" user "Package Geometry/Pastemask Top")
		(15 "B.Paste" user "Package Geometry/Pastemask Bottom")
		(5 "F.SilkS" user "Ref Des/Silkscreen Top")
		(7 "B.SilkS" user "Ref Des/Silkscreen Bottom")
		(1 "F.Mask" user "Board Geometry/Soldermask Top")
		(3 "B.Mask" user "Board Geometry/Soldermask Bottom")
		(17 "Dwgs.User" user "User.Drawings")
		(19 "Cmts.User" user "User.Comments")
		(21 "Eco1.User" user "User.Eco1")
		(23 "Eco2.User" user "User.Eco2")
		(25 "Edge.Cuts" user "Board Geometry/Outline")
		(27 "Margin" user)
		(31 "F.CrtYd" user "Package Geometry/Place Bound Top")
		(29 "B.CrtYd" user "Package Geometry/Place Bound Bottom")
		(35 "F.Fab" user "Ref Des/Assembly Top")
		(33 "B.Fab" user "Ref Des/Assembly Bottom")
	)
	(footprint ""
		(layer "F.Cu")
		(at 278.45512 -35.876738)
		(property "Reference" "R6092"
			(at 0 0 0)
			(layer "F.SilkS")
			(hide yes)
			(effects
				(font
					(size 1.27 1.27)
				)
			)
		)
		(property "Value" ""
			(at 0 0 0)
			(layer "F.Fab")
			(effects
				(font
					(size 1.27 1.27)
				)
			)
		)
		(duplicate_pad_numbers_are_jumpers no)
		(fp_line
			(start -0.7874 -0.4064)
			(end 0.7874 -0.4064)
			(stroke
				(width 0.1524)
				(type default)
			)
			(layer "F.SilkS")
		)
		(fp_line
			(start -0.7874 0.4064)
			(end -0.7874 -0.4064)
			(stroke
				(width 0.1524)
				(type default)
			)
			(layer "F.SilkS")
		)
		(fp_line
			(start 0.7874 -0.4064)
			(end 0.7874 0.4064)
			(stroke
				(width 0.1524)
				(type default)
			)
			(layer "F.SilkS")
		)
		(fp_line
			(start 0.7874 0.4064)
			(end -0.7874 0.4064)
			(stroke
				(width 0.1524)
				(type default)
			)
			(layer "F.SilkS")
		)
		(fp_line
			(start -0.67945 -0.305054)
			(end -0.12065 -0.305054)
			(stroke
				(width 0.1)
				(type default)
			)
			(layer "F.Fab")
		)
		(fp_line
			(start -0.67945 0.3048)
			(end -0.67945 -0.305054)
			(stroke
				(width 0.1)
				(type default)
			)
			(layer "F.Fab")
		)
		(fp_line
			(start -0.12065 -0.305054)
			(end -0.12065 -0.2794)
			(stroke
				(width 0.1)
				(type default)
			)
			(layer "F.Fab")
		)
		(fp_line
			(start -0.12065 -0.2794)
			(end 0.12065 -0.2794)
			(stroke
				(width 0.1)
				(type default)
			)
			(layer "F.Fab")
		)
		(fp_line
			(start -0.12065 0.2794)
			(end -0.12065 0.3048)
			(stroke
				(width 0.1)
				(type default)
			)
			(layer "F.Fab")
		)
		(fp_line
			(start -0.12065 0.3048)
			(end -0.67945 0.3048)
			(stroke
				(width 0.1)
				(type default)
			)
			(layer "F.Fab")
		)
		(fp_line
			(start 0.120396 0.2794)
			(end -0.12065 0.2794)
			(stroke
				(width 0.1)
				(type default)
			)
			(layer "F.Fab")
		)
		(fp_line
			(start 0.120396 0.3048)
			(end 0.120396 0.2794)
			(stroke
				(width 0.1)
				(type default)
			)
			(layer "F.Fab")
		)
		(fp_line
			(start 0.12065 -0.3048)
			(end 0.67945 -0.3048)
			(stroke
				(width 0.1)
				(type default)
			)
			(layer "F.Fab")
		)
		(fp_line
			(start 0.12065 -0.2794)
			(end 0.12065 -0.3048)
			(stroke
				(width 0.1)
				(type default)
			)
			(layer "F.Fab")
		)
		(fp_line
			(start 0.67945 -0.3048)
			(end 0.67945 0.3048)
			(stroke
				(width 0.1)
				(type default)
			)
			(layer "F.Fab")
		)
		(fp_line
			(start 0.67945 0.3048)
			(end 0.120396 0.3048)
			(stroke
				(width 0.1)
				(type default)
			)
			(layer "F.Fab")
		)
		(pad "1" smd circle
			(at -0.40005 0)
			(size 0 0)
			(layers "F.Cu" "F.Mask" "F.Paste")
			(net "P3V3_AUX")
		)
		(pad "2" smd circle
			(at 0.40005 0)
			(size 0 0)
			(layers "F.Cu" "F.Mask" "F.Paste")
			(net "PWRGD_P3V3_SSD10_D")
		)
	)
	(footprint ""
		(layer "F.Cu")
		(at 444.139828 -70.52437 90)
		(property "Reference" "PC443"
			(at 0 0 90)
			(layer "F.SilkS")
			(hide yes)
			(effects
				(font
					(size 1.27 1.27)
				)
			)
		)
		(property "Value" ""
			(at 0 0 90)
			(layer "F.Fab")
			(effects
				(font
					(size 1.27 1.27)
				)
			)
		)
		(duplicate_pad_numbers_are_jumpers no)
		(fp_line
			(start 1.524 -0.762)
			(end 1.524 0.762)
			(stroke
				(width 0.1524)
				(type default)
			)
			(layer "F.SilkS")
		)
		(fp_line
			(start -1.524 -0.762)
			(end 1.524 -0.762)
			(stroke
				(width 0.1524)
				(type default)
			)
			(layer "F.SilkS")
		)
		(fp_line
			(start 1.524 0.762)
			(end -1.524 0.762)
			(stroke
				(width 0.1524)
				(type default)
			)
			(layer "F.SilkS")
		)
		(fp_line
			(start -1.524 0.762)
			(end -1.524 -0.762)
			(stroke
				(width 0.1524)
				(type default)
			)
			(layer "F.SilkS")
		)
		(fp_line
			(start 1.1049 -0.724916)
			(end -1.1049 -0.724916)
			(stroke
				(width 0.1)
				(type default)
			)
			(layer "F.Fab")
		)
		(fp_line
			(start -1.1049 -0.724916)
			(end -1.1049 0.724916)
			(stroke
				(width 0.1)
				(type default)
			)
			(layer "F.Fab")
		)
		(fp_line
			(start 1.1049 0.724916)
			(end 1.1049 -0.724916)
			(stroke
				(width 0.1)
				(type default)
			)
			(layer "F.Fab")
		)
		(fp_line
			(start -1.1049 0.724916)
			(end 1.1049 0.724916)
			(stroke
				(width 0.1)
				(type default)
			)
			(layer "F.Fab")
		)
		(pad "1" smd rect
			(at -0.889 0 270)
			(size 1.016 1.27)
			(layers "F.Cu" "F.Mask" "F.Paste")
			(net "P12V_SSD15_R")
		)
		(pad "2" smd rect
			(at 0.889 0 270)
			(size 1.016 1.27)
			(layers "F.Cu" "F.Mask" "F.Paste")
			(net "GND")
		)
	)
	(footprint ""
		(layer "F.Cu")
		(at 456.818238 -266.91844)
		(property "Reference" "L133"
			(at 0 0 0)
			(layer "F.SilkS")
			(hide yes)
			(effects
				(font
					(size 1.27 1.27)
				)
			)
		)
		(property "Value" ""
			(at 0 0 0)
			(layer "F.Fab")
			(effects
				(font
					(size 1.27 1.27)
				)
			)
		)
		(duplicate_pad_numbers_are_jumpers no)
		(fp_line
			(start -2.248154 -4.9911)
			(end -2.248154 -1.890522)
			(stroke
				(width 0.1524)
				(type default)
			)
			(layer "F.SilkS")
		)
		(fp_line
			(start -2.248154 1.6891)
			(end -2.248154 4.9911)
			(stroke
				(width 0.1524)
				(type default)
			)
			(layer "F.SilkS")
		)
		(fp_line
			(start -2.248154 4.9911)
			(end 2.248154 4.9911)
			(stroke
				(width 0.1524)
				(type default)
			)
			(layer "F.SilkS")
		)
		(fp_line
			(start 2.248154 -4.9911)
			(end -2.248154 -4.9911)
			(stroke
				(width 0.1524)
				(type default)
			)
			(layer "F.SilkS")
		)
		(fp_line
			(start 2.248154 -2.022094)
			(end 2.248154 -4.9911)
			(stroke
				(width 0.1524)
				(type default)
			)
			(layer "F.SilkS")
		)
		(fp_line
			(start 2.248154 4.9911)
			(end 2.248154 1.667002)
			(stroke
				(width 0.1524)
				(type default)
			)
			(layer "F.SilkS")
		)
		(fp_line
			(start -1.700022 -0.899922)
			(end -1.700022 0.899922)
			(stroke
				(width 0.1)
				(type default)
			)
			(layer "F.Fab")
		)
		(fp_line
			(start -1.700022 0.899922)
			(end 1.700022 0.899922)
			(stroke
				(width 0.1)
				(type default)
			)
			(layer "F.Fab")
		)
		(fp_line
			(start 1.700022 -0.899922)
			(end -1.700022 -0.899922)
			(stroke
				(width 0.1)
				(type default)
			)
			(layer "F.Fab")
		)
		(fp_line
			(start 1.700022 0.899922)
			(end 1.700022 -0.899922)
			(stroke
				(width 0.1)
				(type default)
			)
			(layer "F.Fab")
		)
		(pad "1" smd rect
			(at -1.575054 0)
			(size 1.1684 9.8044)
			(layers "F.Cu" "F.Mask" "F.Paste")
			(net "P1V25_PEX3")
		)
		(pad "2" smd rect
			(at 1.575054 0)
			(size 1.1684 9.8044)
			(layers "F.Cu" "F.Mask" "F.Paste")
			(net "P1V25_SERDES_VDDPLL_PEX3")
		)
	)
	(footprint ""
		(layer "F.Cu")
		(at 358.013 -217.424 180)
		(property "Reference" "R4090"
			(at 0 0 180)
			(layer "F.SilkS")
			(hide yes)
			(effects
				(font
					(size 1.27 1.27)
				)
			)
		)
		(property "Value" ""
			(at 0 0 180)
			(layer "F.Fab")
			(effects
				(font
					(size 1.27 1.27)
				)
			)
		)
		(duplicate_pad_numbers_are_jumpers no)
		(fp_line
			(start 0.7874 0.4064)
			(end -0.7874 0.4064)
			(stroke
				(width 0.1524)
				(type default)
			)
			(layer "F.SilkS")
		)
		(fp_line
			(start 0.7874 -0.4064)
			(end 0.7874 0.4064)
			(stroke
				(width 0.1524)
				(type default)
			)
			(layer "F.SilkS")
		)
		(fp_line
			(start -0.7874 0.4064)
			(end -0.7874 -0.4064)
			(stroke
				(width 0.1524)
				(type default)
			)
			(layer "F.SilkS")
		)
		(fp_line
			(start -0.7874 -0.4064)
			(end 0.7874 -0.4064)
			(stroke
				(width 0.1524)
				(type default)
			)
			(layer "F.SilkS")
		)
		(fp_line
			(start 0.67945 0.3048)
			(end 0.120396 0.3048)
			(stroke
				(width 0.1)
				(type default)
			)
			(layer "F.Fab")
		)
		(fp_line
			(start 0.67945 -0.3048)
			(end 0.67945 0.3048)
			(stroke
				(width 0.1)
				(type default)
			)
			(layer "F.Fab")
		)
		(fp_line
			(start 0.12065 -0.2794)
			(end 0.12065 -0.3048)
			(stroke
				(width 0.1)
				(type default)
			)
			(layer "F.Fab")
		)
		(fp_line
			(start 0.12065 -0.3048)
			(end 0.67945 -0.3048)
			(stroke
				(width 0.1)
				(type default)
			)
			(layer "F.Fab")
		)
		(fp_line
			(start 0.120396 0.3048)
			(end 0.120396 0.2794)
			(stroke
				(width 0.1)
				(type default)
			)
			(layer "F.Fab")
		)
		(fp_line
			(start 0.120396 0.2794)
			(end -0.12065 0.2794)
			(stroke
				(width 0.1)
				(type default)
			)
			(layer "F.Fab")
		)
		(fp_line
			(start -0.12065 0.3048)
			(end -0.67945 0.3048)
			(stroke
				(width 0.1)
				(type default)
			)
			(layer "F.Fab")
		)
		(fp_line
			(start -0.12065 0.2794)
			(end -0.12065 0.3048)
			(stroke
				(width 0.1)
				(type default)
			)
			(layer "F.Fab")
		)
		(fp_line
			(start -0.12065 -0.2794)
			(end 0.12065 -0.2794)
			(stroke
				(width 0.1)
				(type default)
			)
			(layer "F.Fab")
		)
		(fp_line
			(start -0.12065 -0.305054)
			(end -0.12065 -0.2794)
			(stroke
				(width 0.1)
				(type default)
			)
			(layer "F.Fab")
		)
		(fp_line
			(start -0.67945 0.3048)
			(end -0.67945 -0.305054)
			(stroke
				(width 0.1)
				(type default)
			)
			(layer "F.Fab")
		)
		(fp_line
			(start -0.67945 -0.305054)
			(end -0.12065 -0.305054)
			(stroke
				(width 0.1)
				(type default)
			)
			(layer "F.Fab")
		)
		(pad "1" smd circle
			(at -0.40005 0 180)
			(size 0 0)
			(layers "F.Cu" "F.Mask" "F.Paste")
			(net "RST_NIC7_PERST_R_N")
		)
		(pad "2" smd circle
			(at 0.40005 0 180)
			(size 0 0)
			(layers "F.Cu" "F.Mask" "F.Paste")
			(net "RST_NIC7_PERST_N")
		)
	)
	(footprint ""
		(layer "F.Cu")
		(at 237.945676 -307.137308 90)
		(property "Reference" "PC257"
			(at 0 0 90)
			(layer "F.SilkS")
			(hide yes)
			(effects
				(font
					(size 1.27 1.27)
				)
			)
		)
		(property "Value" ""
			(at 0 0 90)
			(layer "F.Fab")
			(effects
				(font
					(size 1.27 1.27)
				)
			)
		)
		(duplicate_pad_numbers_are_jumpers no)
		(fp_line
			(start 0.7874 -0.4064)
			(end 0.7874 0.4064)
			(stroke
				(width 0.1524)
				(type default)
			)
			(layer "F.SilkS")
		)
		(fp_line
			(start -0.7874 -0.4064)
			(end 0.7874 -0.4064)
			(stroke
				(width 0.1524)
				(type default)
			)
			(layer "F.SilkS")
		)
		(fp_line
			(start 0.7874 0.4064)
			(end -0.7874 0.4064)
			(stroke
				(width 0.1524)
				(type default)
			)
			(layer "F.SilkS")
		)
		(fp_line
			(start -0.7874 0.4064)
			(end -0.7874 -0.4064)
			(stroke
				(width 0.1524)
				(type default)
			)
			(layer "F.SilkS")
		)
		(fp_line
			(start -0.12065 -0.305054)
			(end -0.12065 -0.2794)
			(stroke
				(width 0.1)
				(type default)
			)
			(layer "F.Fab")
		)
		(fp_line
			(start -0.67945 -0.305054)
			(end -0.12065 -0.305054)
			(stroke
				(width 0.1)
				(type default)
			)
			(layer "F.Fab")
		)
		(fp_line
			(start 0.67945 -0.3048)
			(end 0.67945 0.3048)
			(stroke
				(width 0.1)
				(type default)
			)
			(layer "F.Fab")
		)
		(fp_line
			(start 0.12065 -0.3048)
			(end 0.67945 -0.3048)
			(stroke
				(width 0.1)
				(type default)
			)
			(layer "F.Fab")
		)
		(fp_line
			(start 0.12065 -0.2794)
			(end 0.12065 -0.3048)
			(stroke
				(width 0.1)
				(type default)
			)
			(layer "F.Fab")
		)
		(fp_line
			(start -0.12065 -0.2794)
			(end 0.12065 -0.2794)
			(stroke
				(width 0.1)
				(type default)
			)
			(layer "F.Fab")
		)
		(fp_line
			(start 0.120396 0.2794)
			(end -0.12065 0.2794)
			(stroke
				(width 0.1)
				(type default)
			)
			(layer "F.Fab")
		)
		(fp_line
			(start -0.12065 0.2794)
			(end -0.12065 0.3048)
			(stroke
				(width 0.1)
				(type default)
			)
			(layer "F.Fab")
		)
		(fp_line
			(start 0.67945 0.3048)
			(end 0.120396 0.3048)
			(stroke
				(width 0.1)
				(type default)
			)
			(layer "F.Fab")
		)
		(fp_line
			(start 0.120396 0.3048)
			(end 0.120396 0.2794)
			(stroke
				(width 0.1)
				(type default)
			)
			(layer "F.Fab")
		)
		(fp_line
			(start -0.12065 0.3048)
			(end -0.67945 0.3048)
			(stroke
				(width 0.1)
				(type default)
			)
			(layer "F.Fab")
		)
		(fp_line
			(start -0.67945 0.3048)
			(end -0.67945 -0.305054)
			(stroke
				(width 0.1)
				(type default)
			)
			(layer "F.Fab")
		)
		(pad "1" smd circle
			(at -0.40005 0 90)
			(size 0 0)
			(layers "F.Cu" "F.Mask" "F.Paste")
			(net "P1V25_PEX2_VCC")
		)
		(pad "2" smd circle
			(at 0.40005 0 90)
			(size 0 0)
			(layers "F.Cu" "F.Mask" "F.Paste")
			(net "GND")
		)
	)
	(footprint ""
		(layer "F.Cu")
		(at 162.759644 -61.612526)
		(property "Reference" "PD28"
			(at -3.552444 -2.546604 0)
			(unlocked yes)
			(layer "F.SilkS")
			(effects
				(font
					(size 0.7874 0.5842)
					(thickness 0.1524)
				)
				(justify left)
			)
		)
		(property "Value" ""
			(at 0 0 0)
			(layer "F.Fab")
			(effects
				(font
					(size 1.27 1.27)
				)
			)
		)
		(duplicate_pad_numbers_are_jumpers no)
		(fp_line
			(start -3.656584 -1.970024)
			(end -3.656584 1.970024)
			(stroke
				(width 0.1524)
				(type default)
			)
			(layer "F.SilkS")
		)
		(fp_line
			(start -3.656584 1.970024)
			(end 4.240784 1.970024)
			(stroke
				(width 0.1524)
				(type default)
			)
			(layer "F.SilkS")
		)
		(fp_line
			(start 4.240784 -1.970024)
			(end -3.656584 -1.970024)
			(stroke
				(width 0.1524)
				(type default)
			)
			(layer "F.SilkS")
		)
		(fp_line
			(start 4.240784 1.970024)
			(end 4.240784 -1.970024)
			(stroke
				(width 0.1524)
				(type default)
			)
			(layer "F.SilkS")
		)
		(fp_poly
			(pts
				(xy 3.580384 1.970024) (xy 3.580384 -1.970024) (xy 4.240784 -1.970024) (xy 4.240784 1.970024)
			)
			(stroke
				(width 0)
				(type default)
			)
			(fill yes)
			(layer "F.SilkS")
		)
		(fp_line
			(start -2.3749 -1.970024)
			(end -2.3749 1.970024)
			(stroke
				(width 0.1)
				(type default)
			)
			(layer "F.Fab")
		)
		(fp_line
			(start -2.3749 1.970024)
			(end 2.3749 1.970024)
			(stroke
				(width 0.1)
				(type default)
			)
			(layer "F.Fab")
		)
		(fp_line
			(start 2.3749 -1.970024)
			(end -2.3749 -1.970024)
			(stroke
				(width 0.1)
				(type default)
			)
			(layer "F.Fab")
		)
		(fp_line
			(start 2.3749 1.970024)
			(end 2.3749 -1.970024)
			(stroke
				(width 0.1)
				(type default)
			)
			(layer "F.Fab")
		)
		(fp_text user "+"
			(at -4.9784 -0.23495 0)
			(unlocked yes)
			(layer "F.Fab")
			(effects
				(font
					(size 1.905 1.4224)
					(thickness 0.1524)
				)
				(justify left)
			)
		)
		(fp_text user "-"
			(at 4.1656 -0.23495 0)
			(unlocked yes)
			(layer "F.Fab")
			(effects
				(font
					(size 1.905 1.4224)
					(thickness 0.1524)
				)
				(justify left)
			)
		)
		(pad "A" smd rect
			(at -2.450084 0)
			(size 2.159 2.2606)
			(layers "F.Cu" "F.Mask" "F.Paste")
			(net "GND")
		)
		(pad "C" smd rect
			(at 2.450084 0)
			(size 2.159 2.2606)
			(layers "F.Cu" "F.Mask" "F.Paste")
			(net "P12V_AUX")
		)
	)
	(footprint ""
		(layer "F.Cu")
		(at 45.093128 -343.952322 90)
		(property "Reference" "C2175"
			(at 0 0 90)
			(layer "F.SilkS")
			(hide yes)
			(effects
				(font
					(size 1.27 1.27)
				)
			)
		)
		(property "Value" ""
			(at 0 0 90)
			(layer "F.Fab")
			(effects
				(font
					(size 1.27 1.27)
				)
			)
		)
		(duplicate_pad_numbers_are_jumpers no)
		(fp_line
			(start 0.299974 -0.150114)
			(end 0.299974 0.150114)
			(stroke
				(width 0.1)
				(type default)
			)
			(layer "F.Fab")
		)
		(fp_line
			(start -0.299974 -0.150114)
			(end 0.299974 -0.150114)
			(stroke
				(width 0.1)
				(type default)
			)
			(layer "F.Fab")
		)
		(fp_line
			(start 0.299974 0.150114)
			(end -0.299974 0.150114)
			(stroke
				(width 0.1)
				(type default)
			)
			(layer "F.Fab")
		)
		(fp_line
			(start -0.299974 0.150114)
			(end -0.299974 -0.150114)
			(stroke
				(width 0.1)
				(type default)
			)
			(layer "F.Fab")
		)
		(pad "1" smd rect
			(at -0.2667 0 90)
			(size 0.3048 0.381)
			(layers "F.Cu" "F.Mask" "F.Paste")
			(net "P5E_PEX0_STN4_TX_DN<68>")
		)
		(pad "2" smd rect
			(at 0.2667 0 90)
			(size 0.3048 0.381)
			(layers "F.Cu" "F.Mask" "F.Paste")
			(net "P5E_PEX0_STN4_TX_C_DN<68>")
		)
	)
)
